(kicad_pcb
	(version 20260206)
	(generator "pcbnew")
	(generator_version "10.0")
	(general
		(thickness 1.6)
		(legacy_teardrops no)
	)
	(paper "A4")
	(title_block
		(title "peb — Lightning_PEB_BRD.brd")
		(comment 1 "Lightning (Wiwynn / Facebook NVMe JBOF) / footprints 1618-1624 of 2563")
	)
	(layers
		(0 "F.Cu" signal "TOP")
		(4 "In1.Cu" signal "L2GND")
		(6 "In2.Cu" signal "L3")
		(8 "In3.Cu" signal "L4VCC")
		(10 "In4.Cu" signal "L5VCC")
		(12 "In5.Cu" signal "L6")
		(14 "In6.Cu" signal "L7GND")
		(2 "B.Cu" signal "BOTTOM")
		(9 "F.Adhes" user "F.Adhesive")
		(11 "B.Adhes" user "B.Adhesive")
		(13 "F.Paste" user "Package Geometry/Pastemask Top")
		(15 "B.Paste" user "Package Geometry/Pastemask Bottom")
		(5 "F.SilkS" user "Ref Des/Silkscreen Top")
		(7 "B.SilkS" user "Ref Des/Silkscreen Bottom")
		(1 "F.Mask" user "Board Geometry/Soldermask Top")
		(3 "B.Mask" user "Board Geometry/Soldermask Bottom")
		(17 "Dwgs.User" user "User.Drawings")
		(19 "Cmts.User" user "User.Comments")
		(21 "Eco1.User" user "User.Eco1")
		(23 "Eco2.User" user "User.Eco2")
		(25 "Edge.Cuts" user "Board Geometry/Outline")
		(27 "Margin" user)
		(31 "F.CrtYd" user "Package Geometry/Place Bound Top")
		(29 "B.CrtYd" user "Package Geometry/Place Bound Bottom")
		(35 "F.Fab" user "Ref Des/Assembly Top")
		(33 "B.Fab" user "Ref Des/Assembly Bottom")
	)
	(footprint ""
		(layer "F.Cu")
		(at 27.494738 -95.226124 180)
		(property "Reference" "Q41"
			(at 0 0 180)
			(layer "F.SilkS")
			(hide yes)
			(effects
				(font
					(size 1.27 1.27)
				)
			)
		)
		(property "Value" "TMBT3904-GP"
			(at 0.10287 -10.29843 180)
			(unlocked yes)
			(layer "F.Fab")
			(hide yes)
			(effects
				(font
					(size 1.016 1.016)
					(thickness 0.1524)
				)
			)
		)
		(property "Device Type" "SOT23CBE2D4H44"
			(at 0.10287 -12.20343 180)
			(unlocked yes)
			(layer "F.Fab")
			(hide yes)
			(effects
				(font
					(size 1.016 1.016)
					(thickness 0.1524)
				)
			)
		)
		(duplicate_pad_numbers_are_jumpers no)
		(fp_line
			(start 1.651 1.778)
			(end 1.651 -1.778)
			(stroke
				(width 0.1524)
				(type default)
			)
			(layer "F.SilkS")
		)
		(fp_line
			(start 1.651 -1.778)
			(end -1.651 -1.778)
			(stroke
				(width 0.1524)
				(type default)
			)
			(layer "F.SilkS")
		)
		(fp_line
			(start -1.651 1.778)
			(end 1.651 1.778)
			(stroke
				(width 0.1524)
				(type default)
			)
			(layer "F.SilkS")
		)
		(fp_line
			(start -1.651 -1.778)
			(end -1.651 1.778)
			(stroke
				(width 0.1524)
				(type default)
			)
			(layer "F.SilkS")
		)
		(fp_poly
			(pts
				(xy -1.778 1.8796) (xy -1.778 -1.8796) (xy 1.778 -1.8796) (xy 1.778 1.8796)
			)
			(stroke
				(width 0)
				(type default)
			)
			(fill no)
			(layer "F.CrtYd")
		)
		(fp_poly
			(pts
				(xy -1.778 1.8796) (xy -1.778 -1.8796) (xy 1.778 -1.8796) (xy 1.778 1.8796)
			)
			(stroke
				(width 0)
				(type default)
			)
			(fill no)
			(layer "F.Fab")
		)
		(pad "B" smd custom
			(at -0.98425 0.9525 180)
			(size 0.1905 0.1905)
			(layers "F.Cu" "F.Mask" "F.Paste")
			(net "FM_TPM_PRES_RST")
			(options
				(clearance outline)
				(anchor circle)
			)
			(primitives
				(gr_poly
					(pts
						(arc
							(start -0.1778 0.5715)
							(mid -0.321484 0.511984)
							(end -0.381 0.3683)
						)
						(arc
							(start -0.381 -0.3683)
							(mid -0.321484 -0.511984)
							(end -0.1778 -0.5715)
						)
						(arc
							(start 0.1778 -0.5715)
							(mid 0.321484 -0.511984)
							(end 0.381 -0.3683)
						)
						(arc
							(start 0.381 0.3683)
							(mid 0.321484 0.511984)
							(end 0.1778 0.5715)
						)
					)
					(width 0)
					(fill yes)
				)
			)
		)
		(pad "C" smd custom
			(at 0 -0.9525 180)
			(size 0.1905 0.1905)
			(layers "F.Cu" "F.Mask" "F.Paste")
			(net "RST_BMC_EXTRST_N")
			(options
				(clearance outline)
				(anchor circle)
			)
			(primitives
				(gr_poly
					(pts
						(arc
							(start -0.1778 0.5715)
							(mid -0.321484 0.511984)
							(end -0.381 0.3683)
						)
						(arc
							(start -0.381 -0.3683)
							(mid -0.321484 -0.511984)
							(end -0.1778 -0.5715)
						)
						(arc
							(start 0.1778 -0.5715)
							(mid 0.321484 -0.511984)
							(end 0.381 -0.3683)
						)
						(arc
							(start 0.381 0.3683)
							(mid 0.321484 0.511984)
							(end 0.1778 0.5715)
						)
					)
					(width 0)
					(fill yes)
				)
			)
		)
		(pad "E" smd custom
			(at 0.98425 0.9525 180)
			(size 0.1905 0.1905)
			(layers "F.Cu" "F.Mask" "F.Paste")
			(net "GND")
			(options
				(clearance outline)
				(anchor circle)
			)
			(primitives
				(gr_poly
					(pts
						(arc
							(start -0.1778 0.5715)
							(mid -0.321484 0.511984)
							(end -0.381 0.3683)
						)
						(arc
							(start -0.381 -0.3683)
							(mid -0.321484 -0.511984)
							(end -0.1778 -0.5715)
						)
						(arc
							(start 0.1778 -0.5715)
							(mid 0.321484 -0.511984)
							(end 0.381 -0.3683)
						)
						(arc
							(start 0.381 0.3683)
							(mid 0.321484 0.511984)
							(end 0.1778 0.5715)
						)
					)
					(width 0)
					(fill yes)
				)
			)
		)
	)
	(footprint ""
		(layer "F.Cu")
		(at 145.177002 -73.306432 -90)
		(property "Reference" "PC196"
			(at 0 0 270)
			(layer "F.SilkS")
			(hide yes)
			(effects
				(font
					(size 1.27 1.27)
				)
			)
		)
		(property "Value" "SC22U25V6KX-GP-U"
			(at -2.860802 -5.279644 270)
			(unlocked yes)
			(layer "F.Fab")
			(hide yes)
			(effects
				(font
					(size 1.016 1.016)
					(thickness 0.1524)
				)
			)
		)
		(property "Device Type" "C1206-TO0D3H75"
			(at -2.860802 -6.803644 270)
			(unlocked yes)
			(layer "F.Fab")
			(hide yes)
			(effects
				(font
					(size 1.016 1.016)
					(thickness 0.1524)
				)
			)
		)
		(duplicate_pad_numbers_are_jumpers no)
		(fp_line
			(start -1.3081 2.3749)
			(end -1.3081 -2.3749)
			(stroke
				(width 0.1524)
				(type default)
			)
			(layer "F.SilkS")
		)
		(fp_line
			(start 1.3081 2.3749)
			(end -1.3081 2.3749)
			(stroke
				(width 0.1524)
				(type default)
			)
			(layer "F.SilkS")
		)
		(fp_line
			(start -1.3081 -2.3749)
			(end 1.3081 -2.3749)
			(stroke
				(width 0.1524)
				(type default)
			)
			(layer "F.SilkS")
		)
		(fp_line
			(start 1.3081 -2.3749)
			(end 1.3081 2.3749)
			(stroke
				(width 0.1524)
				(type default)
			)
			(layer "F.SilkS")
		)
		(fp_rect
			(start -0.8001 1.6002)
			(end 0.8001 -1.6002)
			(stroke
				(width 0)
				(type default)
			)
			(fill no)
			(layer "F.CrtYd")
		)
		(fp_poly
			(pts
				(xy -1.5621 2.4511) (xy -1.5621 1.6002) (xy 0.8001 1.6002) (xy 0.8001 -1.6002) (xy -0.8001 -1.6002)
				(xy -0.8001 1.5875) (xy -1.5621 1.5875) (xy -1.5621 -2.4511) (xy 1.5621 -2.4511) (xy 1.5621 2.4511)
			)
			(stroke
				(width 0)
				(type default)
			)
			(fill no)
			(layer "F.CrtYd")
		)
		(fp_rect
			(start -1.5621 2.4511)
			(end 1.5621 -2.4511)
			(stroke
				(width 0)
				(type default)
			)
			(fill no)
			(layer "F.Fab")
		)
		(pad "1" smd rect
			(at 0 -1.392936 270)
			(size 2.1082 1.4478)
			(layers "F.Cu" "F.Mask" "F.Paste")
			(net "P0V9_VIN")
		)
		(pad "2" smd rect
			(at 0 1.392936 270)
			(size 2.1082 1.4478)
			(layers "F.Cu" "F.Mask" "F.Paste")
			(net "GND")
		)
	)
	(footprint ""
		(layer "F.Cu")
		(at 125.599952 -13.999972 90)
		(property "Reference" "LED9"
			(at 0 0 90)
			(layer "F.SilkS")
			(hide yes)
			(effects
				(font
					(size 1.27 1.27)
				)
			)
		)
		(property "Value" "LED-YG-51-GP"
			(at -2.6924 -1.4224 90)
			(unlocked yes)
			(layer "F.Fab")
			(hide yes)
			(effects
				(font
					(size 1.016 1.016)
					(thickness 0.1524)
				)
			)
		)
		(property "Device Type" "LED1608AKH40"
			(at -2.6924 -2.9464 90)
			(unlocked yes)
			(layer "F.Fab")
			(hide yes)
			(effects
				(font
					(size 1.016 1.016)
					(thickness 0.1524)
				)
			)
		)
		(duplicate_pad_numbers_are_jumpers no)
		(fp_line
			(start 0.6604 -1.3716)
			(end 0.6604 1.3716)
			(stroke
				(width 0.1524)
				(type default)
			)
			(layer "F.SilkS")
		)
		(fp_line
			(start -0.6604 -1.3716)
			(end 0.6604 -1.3716)
			(stroke
				(width 0.1524)
				(type default)
			)
			(layer "F.SilkS")
		)
		(fp_line
			(start 0.6604 1.3716)
			(end -0.6604 1.3716)
			(stroke
				(width 0.1524)
				(type default)
			)
			(layer "F.SilkS")
		)
		(fp_line
			(start -0.6604 1.3716)
			(end -0.6604 -1.3716)
			(stroke
				(width 0.1524)
				(type default)
			)
			(layer "F.SilkS")
		)
		(fp_line
			(start -0.5969 1.5494)
			(end 0.5842 1.5494)
			(stroke
				(width 0.508)
				(type default)
			)
			(layer "F.SilkS")
		)
		(fp_line
			(start 0.7493 1.651)
			(end 0.7493 1.1811)
			(stroke
				(width 0.3302)
				(type default)
			)
			(layer "F.SilkS")
		)
		(fp_line
			(start -0.7493 1.651)
			(end -0.7493 1.1811)
			(stroke
				(width 0.3302)
				(type default)
			)
			(layer "F.SilkS")
		)
		(fp_rect
			(start -0.6223 1.3335)
			(end 0.6223 -1.3335)
			(stroke
				(width 0)
				(type default)
			)
			(fill no)
			(layer "F.CrtYd")
		)
		(fp_rect
			(start -0.6223 1.3335)
			(end 0.6223 -1.3335)
			(stroke
				(width 0)
				(type default)
			)
			(fill no)
			(layer "F.Fab")
		)
		(pad "A" smd custom
			(at 0 -0.762 90)
			(size 0.2159 0.2159)
			(layers "F.Cu" "F.Mask" "F.Paste")
			(net "LED_R_2")
			(options
				(clearance outline)
				(anchor circle)
			)
			(primitives
				(gr_poly
					(pts
						(arc
							(start -0.3302 -0.4318)
							(mid -0.402042 -0.402042)
							(end -0.4318 -0.3302)
						)
						(arc
							(start -0.4318 0.3302)
							(mid -0.402042 0.402042)
							(end -0.3302 0.4318)
						)
						(arc
							(start 0.3302 0.4318)
							(mid 0.402042 0.402042)
							(end 0.4318 0.3302)
						)
						(arc
							(start 0.4318 -0.3302)
							(mid 0.402042 -0.402042)
							(end 0.3302 -0.4318)
						)
					)
					(width 0)
					(fill yes)
				)
			)
		)
		(pad "K" smd custom
			(at 0 0.762 90)
			(size 0.2159 0.2159)
			(layers "F.Cu" "F.Mask" "F.Paste")
			(net "LED_Q_2")
			(options
				(clearance outline)
				(anchor circle)
			)
			(primitives
				(gr_poly
					(pts
						(arc
							(start -0.3302 -0.4318)
							(mid -0.402042 -0.402042)
							(end -0.4318 -0.3302)
						)
						(arc
							(start -0.4318 0.3302)
							(mid -0.402042 0.402042)
							(end -0.3302 0.4318)
						)
						(arc
							(start 0.3302 0.4318)
							(mid 0.402042 0.402042)
							(end 0.4318 0.3302)
						)
						(arc
							(start 0.4318 -0.3302)
							(mid 0.402042 -0.402042)
							(end 0.3302 -0.4318)
						)
					)
					(width 0)
					(fill yes)
				)
			)
		)
	)
	(footprint ""
		(layer "F.Cu")
		(at 181.61 -22.479 -90)
		(property "Reference" "C404"
			(at 0 0 270)
			(layer "F.SilkS")
			(hide yes)
			(effects
				(font
					(size 1.27 1.27)
				)
			)
		)
		(property "Value" "SCD22U10V2KX-1GP"
			(at 1.1811 -2.7051 270)
			(unlocked yes)
			(layer "F.Fab")
			(hide yes)
			(effects
				(font
					(size 1.016 1.016)
					(thickness 0.1524)
				)
			)
		)
		(property "Device Type" "C402H22"
			(at 1.1811 -4.2291 270)
			(unlocked yes)
			(layer "F.Fab")
			(hide yes)
			(effects
				(font
					(size 1.016 1.016)
					(thickness 0.1524)
				)
			)
		)
		(duplicate_pad_numbers_are_jumpers no)
		(fp_rect
			(start -0.4318 0.9525)
			(end 0.4318 -0.9525)
			(stroke
				(width 0)
				(type default)
			)
			(fill no)
			(layer "F.CrtYd")
		)
		(fp_rect
			(start -0.4318 0.9525)
			(end 0.4318 -0.9525)
			(stroke
				(width 0)
				(type default)
			)
			(fill no)
			(layer "F.Fab")
		)
		(pad "1" smd custom
			(at 0 -0.4445 270)
			(size 0.1524 0.1524)
			(layers "F.Cu" "F.Mask" "F.Paste")
			(net "PCIE_TX_CAP_P92")
			(options
				(clearance outline)
				(anchor circle)
			)
			(primitives
				(gr_poly
					(pts
						(arc
							(start 0.3048 -0.2032)
							(mid 0.275042 -0.275042)
							(end 0.2032 -0.3048)
						)
						(arc
							(start -0.2032 -0.3048)
							(mid -0.275042 -0.275042)
							(end -0.3048 -0.2032)
						)
						(arc
							(start -0.3048 0.2032)
							(mid -0.275042 0.275042)
							(end -0.2032 0.3048)
						)
						(arc
							(start 0.2032 0.3048)
							(mid 0.275042 0.275042)
							(end 0.3048 0.2032)
						)
					)
					(width 0)
					(fill yes)
				)
			)
		)
		(pad "2" smd custom
			(at 0 0.4445 270)
			(size 0.1524 0.1524)
			(layers "F.Cu" "F.Mask" "F.Paste")
			(net "PCIE_TX_P92")
			(options
				(clearance outline)
				(anchor circle)
			)
			(primitives
				(gr_poly
					(pts
						(arc
							(start 0.3048 -0.2032)
							(mid 0.275042 -0.275042)
							(end 0.2032 -0.3048)
						)
						(arc
							(start -0.2032 -0.3048)
							(mid -0.275042 -0.275042)
							(end -0.3048 -0.2032)
						)
						(arc
							(start -0.3048 0.2032)
							(mid -0.275042 0.275042)
							(end -0.2032 0.3048)
						)
						(arc
							(start 0.2032 0.3048)
							(mid 0.275042 0.275042)
							(end 0.3048 0.2032)
						)
					)
					(width 0)
					(fill yes)
				)
			)
		)
	)
	(footprint ""
		(layer "F.Cu")
		(at 64.52108 -147.670774 -90)
		(property "Reference" "R200"
			(at 0 0 270)
			(layer "F.SilkS")
			(hide yes)
			(effects
				(font
					(size 1.27 1.27)
				)
			)
		)
		(property "Value" "8K2R2J-3-GP"
			(at 0.064008 -3.993896 270)
			(unlocked yes)
			(layer "F.Fab")
			(hide yes)
			(effects
				(font
					(size 1.016 1.016)
					(thickness 0.1524)
				)
			)
		)
		(property "Device Type" "R402H16"
			(at 0.064008 -5.517896 270)
			(unlocked yes)
			(layer "F.Fab")
			(hide yes)
			(effects
				(font
					(size 1.016 1.016)
					(thickness 0.1524)
				)
			)
		)
		(duplicate_pad_numbers_are_jumpers no)
		(fp_line
			(start -0.508 -0.9398)
			(end -0.508 0.9398)
			(stroke
				(width 0.1524)
				(type default)
			)
			(layer "F.SilkS")
		)
		(fp_line
			(start 0.508 -0.9398)
			(end -0.508 -0.9398)
			(stroke
				(width 0.1524)
				(type default)
			)
			(layer "F.SilkS")
		)
		(fp_rect
			(start -0.508 0.9398)
			(end 0.508 -0.9398)
			(stroke
				(width 0)
				(type default)
			)
			(fill no)
			(layer "F.CrtYd")
		)
		(fp_rect
			(start -0.508 0.9398)
			(end 0.508 -0.9398)
			(stroke
				(width 0)
				(type default)
			)
			(fill no)
			(layer "F.Fab")
		)
		(pad "1" smd custom
			(at 0 -0.4445 270)
			(size 0.1397 0.1397)
			(layers "F.Cu" "F.Mask" "F.Paste")
			(net "EEPROM_WP")
			(options
				(clearance outline)
				(anchor circle)
			)
			(primitives
				(gr_poly
					(pts
						(arc
							(start -0.1778 -0.2794)
							(mid -0.249642 -0.249642)
							(end -0.2794 -0.1778)
						)
						(arc
							(start -0.2794 0.1778)
							(mid -0.249642 0.249642)
							(end -0.1778 0.2794)
						)
						(arc
							(start 0.1778 0.2794)
							(mid 0.249642 0.249642)
							(end 0.2794 0.1778)
						)
						(arc
							(start 0.2794 -0.1778)
							(mid 0.249642 -0.249642)
							(end 0.1778 -0.2794)
						)
					)
					(width 0)
					(fill yes)
				)
			)
		)
		(pad "2" smd custom
			(at 0 0.4445 270)
			(size 0.1397 0.1397)
			(layers "F.Cu" "F.Mask" "F.Paste")
			(net "GND")
			(options
				(clearance outline)
				(anchor circle)
			)
			(primitives
				(gr_poly
					(pts
						(arc
							(start -0.1778 -0.2794)
							(mid -0.249642 -0.249642)
							(end -0.2794 -0.1778)
						)
						(arc
							(start -0.2794 0.1778)
							(mid -0.249642 0.249642)
							(end -0.1778 0.2794)
						)
						(arc
							(start 0.1778 0.2794)
							(mid 0.249642 0.249642)
							(end 0.2794 0.1778)
						)
						(arc
							(start 0.2794 -0.1778)
							(mid 0.249642 -0.249642)
							(end 0.1778 -0.2794)
						)
					)
					(width 0)
					(fill yes)
				)
			)
		)
	)
	(footprint ""
		(layer "F.Cu")
		(at 67.749166 -88.30056)
		(property "Reference" "R482"
			(at 0 0 0)
			(layer "F.SilkS")
			(hide yes)
			(effects
				(font
					(size 1.27 1.27)
				)
			)
		)
		(property "Value" "0R2J-2-GP"
			(at 0.064008 -3.993896 0)
			(unlocked yes)
			(layer "F.Fab")
			(hide yes)
			(effects
				(font
					(size 1.016 1.016)
					(thickness 0.1524)
				)
			)
		)
		(property "Device Type" "R402H16"
			(at 0.064008 -5.517896 0)
			(unlocked yes)
			(layer "F.Fab")
			(hide yes)
			(effects
				(font
					(size 1.016 1.016)
					(thickness 0.1524)
				)
			)
		)
		(duplicate_pad_numbers_are_jumpers no)
		(fp_line
			(start -0.508 -0.9398)
			(end -0.508 0.9398)
			(stroke
				(width 0.1524)
				(type default)
			)
			(layer "F.SilkS")
		)
		(fp_line
			(start 0.508 -0.9398)
			(end -0.508 -0.9398)
			(stroke
				(width 0.1524)
				(type default)
			)
			(layer "F.SilkS")
		)
		(fp_rect
			(start -0.508 0.9398)
			(end 0.508 -0.9398)
			(stroke
				(width 0)
				(type default)
			)
			(fill no)
			(layer "F.CrtYd")
		)
		(fp_rect
			(start -0.508 0.9398)
			(end 0.508 -0.9398)
			(stroke
				(width 0)
				(type default)
			)
			(fill no)
			(layer "F.Fab")
		)
		(pad "1" smd custom
			(at 0 -0.4445)
			(size 0.1397 0.1397)
			(layers "F.Cu" "F.Mask" "F.Paste")
			(net "HB_A_OUT")
			(options
				(clearance outline)
				(anchor circle)
			)
			(primitives
				(gr_poly
					(pts
						(arc
							(start -0.1778 -0.2794)
							(mid -0.249642 -0.249642)
							(end -0.2794 -0.1778)
						)
						(arc
							(start -0.2794 0.1778)
							(mid -0.249642 0.249642)
							(end -0.1778 0.2794)
						)
						(arc
							(start 0.1778 0.2794)
							(mid 0.249642 0.249642)
							(end 0.2794 0.1778)
						)
						(arc
							(start 0.2794 -0.1778)
							(mid 0.249642 -0.249642)
							(end 0.1778 -0.2794)
						)
					)
					(width 0)
					(fill yes)
				)
			)
		)
		(pad "2" smd custom
			(at 0 0.4445)
			(size 0.1397 0.1397)
			(layers "F.Cu" "F.Mask" "F.Paste")
			(net "INVERTER_G1")
			(options
				(clearance outline)
				(anchor circle)
			)
			(primitives
				(gr_poly
					(pts
						(arc
							(start -0.1778 -0.2794)
							(mid -0.249642 -0.249642)
							(end -0.2794 -0.1778)
						)
						(arc
							(start -0.2794 0.1778)
							(mid -0.249642 0.249642)
							(end -0.1778 0.2794)
						)
						(arc
							(start 0.1778 0.2794)
							(mid 0.249642 0.249642)
							(end 0.2794 0.1778)
						)
						(arc
							(start 0.2794 -0.1778)
							(mid 0.249642 -0.249642)
							(end 0.1778 -0.2794)
						)
					)
					(width 0)
					(fill yes)
				)
			)
		)
	)
	(footprint ""
		(layer "F.Cu")
		(at 159.385 -95.9104 180)
		(property "Reference" "R61"
			(at 0 0 180)
			(layer "F.SilkS")
			(hide yes)
			(effects
				(font
					(size 1.27 1.27)
				)
			)
		)
		(property "Value" "10KR2F-2-GP"
			(at 0.064008 -3.993896 180)
			(unlocked yes)
			(layer "F.Fab")
			(hide yes)
			(effects
				(font
					(size 1.016 1.016)
					(thickness 0.1524)
				)
			)
		)
		(property "Device Type" "R402H16"
			(at 0.064008 -5.517896 180)
			(unlocked yes)
			(layer "F.Fab")
			(hide yes)
			(effects
				(font
					(size 1.016 1.016)
					(thickness 0.1524)
				)
			)
		)
		(duplicate_pad_numbers_are_jumpers no)
		(fp_line
			(start 0.508 -0.9398)
			(end -0.508 -0.9398)
			(stroke
				(width 0.1524)
				(type default)
			)
			(layer "F.SilkS")
		)
		(fp_line
			(start -0.508 -0.9398)
			(end -0.508 0.9398)
			(stroke
				(width 0.1524)
				(type default)
			)
			(layer "F.SilkS")
		)
		(fp_rect
			(start -0.508 0.9398)
			(end 0.508 -0.9398)
			(stroke
				(width 0)
				(type default)
			)
			(fill no)
			(layer "F.CrtYd")
		)
		(fp_rect
			(start -0.508 0.9398)
			(end 0.508 -0.9398)
			(stroke
				(width 0)
				(type default)
			)
			(fill no)
			(layer "F.Fab")
		)
		(pad "1" smd custom
			(at 0 -0.4445 180)
			(size 0.1397 0.1397)
			(layers "F.Cu" "F.Mask" "F.Paste")
			(net "GND")
			(options
				(clearance outline)
				(anchor circle)
			)
			(primitives
				(gr_poly
					(pts
						(arc
							(start -0.1778 -0.2794)
							(mid -0.249642 -0.249642)
							(end -0.2794 -0.1778)
						)
						(arc
							(start -0.2794 0.1778)
							(mid -0.249642 0.249642)
							(end -0.1778 0.2794)
						)
						(arc
							(start 0.1778 0.2794)
							(mid 0.249642 0.249642)
							(end 0.2794 0.1778)
						)
						(arc
							(start 0.2794 -0.1778)
							(mid 0.249642 -0.249642)
							(end 0.1778 -0.2794)
						)
					)
					(width 0)
					(fill yes)
				)
			)
		)
		(pad "2" smd custom
			(at 0 0.4445 180)
			(size 0.1397 0.1397)
			(layers "F.Cu" "F.Mask" "F.Paste")
			(net "CLKGEN_OE3")
			(options
				(clearance outline)
				(anchor circle)
			)
			(primitives
				(gr_poly
					(pts
						(arc
							(start -0.1778 -0.2794)
							(mid -0.249642 -0.249642)
							(end -0.2794 -0.1778)
						)
						(arc
							(start -0.2794 0.1778)
							(mid -0.249642 0.249642)
							(end -0.1778 0.2794)
						)
						(arc
							(start 0.1778 0.2794)
							(mid 0.249642 0.249642)
							(end 0.2794 0.1778)
						)
						(arc
							(start 0.2794 -0.1778)
							(mid 0.249642 -0.249642)
							(end 0.1778 -0.2794)
						)
					)
					(width 0)
					(fill yes)
				)
			)
		)
	)
)
